(kicad_pcb
	(version 20260206)
	(generator "pcbnew")
	(generator_version "10.0")
	(general
		(thickness 1.6)
		(legacy_teardrops no)
	)
	(paper "A4")
	(title_block
		(title "Wiwynn_Tioga_Pass_MB.brd")
		(comment 1 "Tioga Pass / footprint 990 of 4770 (J4B1), pads 124-243 of 291")
	)
	(layers
		(0 "F.Cu" signal "TOP")
		(4 "In1.Cu" signal "L2GND")
		(6 "In2.Cu" signal "L3")
		(8 "In3.Cu" signal "L4GND")
		(10 "In4.Cu" signal "L5")
		(12 "In5.Cu" signal "L6GND")
		(14 "In6.Cu" signal "L7VCC")
		(16 "In7.Cu" signal "L8VCC")
		(18 "In8.Cu" signal "L9GND")
		(20 "In9.Cu" signal "L10")
		(22 "In10.Cu" signal "L11GND")
		(24 "In11.Cu" signal "L12")
		(26 "In12.Cu" signal "L13GND")
		(2 "B.Cu" signal "BOTTOM")
		(9 "F.Adhes" user "F.Adhesive")
		(11 "B.Adhes" user "B.Adhesive")
		(13 "F.Paste" user "Package Geometry/Pastemask Top")
		(15 "B.Paste" user "Package Geometry/Pastemask Bottom")
		(5 "F.SilkS" user "Ref Des/Silkscreen Top")
		(7 "B.SilkS" user "Ref Des/Silkscreen Bottom")
		(1 "F.Mask" user "Board Geometry/Soldermask Top")
		(3 "B.Mask" user "Board Geometry/Soldermask Bottom")
		(17 "Dwgs.User" user "User.Drawings")
		(19 "Cmts.User" user "User.Comments")
		(21 "Eco1.User" user "User.Eco1")
		(23 "Eco2.User" user "User.Eco2")
		(25 "Edge.Cuts" user "Board Geometry/Outline")
		(27 "Margin" user)
		(31 "F.CrtYd" user "Package Geometry/Place Bound Top")
		(29 "B.CrtYd" user "Package Geometry/Place Bound Bottom")
		(35 "F.Fab" user "Ref Des/Assembly Top")
		(33 "B.Fab" user "Ref Des/Assembly Bottom")
	)
	(footprint ""
		(layer "F.Cu")
		(at 194.700398 -133.0706 90)
		(property "Reference" "J4B1"
			(at -5.087112 42.28211 0)
			(unlocked yes)
			(layer "F.SilkS")
			(effects
				(font
					(size 0.7874 0.5842)
					(thickness 0.1524)
				)
				(justify left)
			)
		)
		(property "Value" ""
			(at 0 0 90)
			(layer "F.Fab")
			(effects
				(font
					(size 1.27 1.27)
				)
			)
		)
		(duplicate_pad_numbers_are_jumpers no)
		(pad "121" smd rect
			(at 0 107.100116 90)
			(size 1.8034 0.508)
			(layers "F.Cu" "F.Mask" "F.Paste")
			(net "M_D_DQS_DP<15>")
		)
		(pad "122" smd rect
			(at 0 107.95 90)
			(size 1.8034 0.508)
			(layers "F.Cu" "F.Mask" "F.Paste")
			(net "M_D_DQS_DN<15>")
		)
		(pad "123" smd rect
			(at 0 108.799884 90)
			(size 1.8034 0.508)
			(layers "F.Cu" "F.Mask" "F.Paste")
			(net "GND")
		)
		(pad "124" smd rect
			(at 0 109.650022 90)
			(size 1.8034 0.508)
			(layers "F.Cu" "F.Mask" "F.Paste")
			(net "M_D_DQ<55>")
		)
		(pad "125" smd rect
			(at 0 110.499906 90)
			(size 1.8034 0.508)
			(layers "F.Cu" "F.Mask" "F.Paste")
			(net "GND")
		)
		(pad "126" smd rect
			(at 0 111.350044 90)
			(size 1.8034 0.508)
			(layers "F.Cu" "F.Mask" "F.Paste")
			(net "M_D_DQ<51>")
		)
		(pad "127" smd rect
			(at 0 112.199928 90)
			(size 1.8034 0.508)
			(layers "F.Cu" "F.Mask" "F.Paste")
			(net "GND")
		)
		(pad "128" smd rect
			(at 0 113.050066 90)
			(size 1.8034 0.508)
			(layers "F.Cu" "F.Mask" "F.Paste")
			(net "M_D_DQ<61>")
		)
		(pad "129" smd rect
			(at 0 113.89995 90)
			(size 1.8034 0.508)
			(layers "F.Cu" "F.Mask" "F.Paste")
			(net "GND")
		)
		(pad "130" smd rect
			(at 0 114.750088 90)
			(size 1.8034 0.508)
			(layers "F.Cu" "F.Mask" "F.Paste")
			(net "M_D_DQ<57>")
		)
		(pad "131" smd rect
			(at 0 115.599972 90)
			(size 1.8034 0.508)
			(layers "F.Cu" "F.Mask" "F.Paste")
			(net "GND")
		)
		(pad "132" smd rect
			(at 0 116.45011 90)
			(size 1.8034 0.508)
			(layers "F.Cu" "F.Mask" "F.Paste")
			(net "M_D_DQS_DP<16>")
		)
		(pad "133" smd rect
			(at 0 117.299994 90)
			(size 1.8034 0.508)
			(layers "F.Cu" "F.Mask" "F.Paste")
			(net "M_D_DQS_DN<16>")
		)
		(pad "134" smd rect
			(at 0 118.149878 90)
			(size 1.8034 0.508)
			(layers "F.Cu" "F.Mask" "F.Paste")
			(net "GND")
		)
		(pad "135" smd rect
			(at 0 119.000016 90)
			(size 1.8034 0.508)
			(layers "F.Cu" "F.Mask" "F.Paste")
			(net "M_D_DQ<63>")
		)
		(pad "136" smd rect
			(at 0 119.8499 90)
			(size 1.8034 0.508)
			(layers "F.Cu" "F.Mask" "F.Paste")
			(net "GND")
		)
		(pad "137" smd rect
			(at 0 120.700038 90)
			(size 1.8034 0.508)
			(layers "F.Cu" "F.Mask" "F.Paste")
			(net "M_D_DQ<59>")
		)
		(pad "138" smd rect
			(at 0 121.549922 90)
			(size 1.8034 0.508)
			(layers "F.Cu" "F.Mask" "F.Paste")
			(net "GND")
		)
		(pad "139" smd rect
			(at 0 122.40006 90)
			(size 1.8034 0.508)
			(layers "F.Cu" "F.Mask" "F.Paste")
			(net "GND")
		)
		(pad "140" smd rect
			(at 0 123.249944 90)
			(size 1.8034 0.508)
			(layers "F.Cu" "F.Mask" "F.Paste")
			(net "GND")
		)
		(pad "141" smd rect
			(at 0 124.100082 90)
			(size 1.8034 0.508)
			(layers "F.Cu" "F.Mask" "F.Paste")
			(net "SMB_DDR_DEF_VPP_SCL")
		)
		(pad "142" smd rect
			(at 0 124.949966 90)
			(size 1.8034 0.508)
			(layers "F.Cu" "F.Mask" "F.Paste")
			(net "PVPP_DEF")
		)
		(pad "143" smd rect
			(at 0 125.800104 90)
			(size 1.8034 0.508)
			(layers "F.Cu" "F.Mask" "F.Paste")
			(net "PVPP_DEF")
		)
		(pad "144" smd rect
			(at 0 126.649988 90)
			(size 1.8034 0.508)
			(layers "F.Cu" "F.Mask" "F.Paste")
			(net "TP_CH_D_DIMM_D0_RFU_2")
		)
		(pad "145" smd rect
			(at 4.59994 0 90)
			(size 1.8034 0.508)
			(layers "F.Cu" "F.Mask" "F.Paste")
			(net "P12V_NVDIMM_DEF")
		)
		(pad "146" smd rect
			(at 4.59994 0.849884 90)
			(size 1.8034 0.508)
			(layers "F.Cu" "F.Mask" "F.Paste")
			(net "M_D_VREF")
		)
		(pad "147" smd rect
			(at 4.59994 1.700022 90)
			(size 1.8034 0.508)
			(layers "F.Cu" "F.Mask" "F.Paste")
			(net "GND")
		)
		(pad "148" smd rect
			(at 4.59994 2.549906 90)
			(size 1.8034 0.508)
			(layers "F.Cu" "F.Mask" "F.Paste")
			(net "M_D_DQ<4>")
		)
		(pad "149" smd rect
			(at 4.59994 3.400044 90)
			(size 1.8034 0.508)
			(layers "F.Cu" "F.Mask" "F.Paste")
			(net "GND")
		)
		(pad "150" smd rect
			(at 4.59994 4.249928 90)
			(size 1.8034 0.508)
			(layers "F.Cu" "F.Mask" "F.Paste")
			(net "M_D_DQ<0>")
		)
		(pad "151" smd rect
			(at 4.59994 5.100066 90)
			(size 1.8034 0.508)
			(layers "F.Cu" "F.Mask" "F.Paste")
			(net "GND")
		)
		(pad "152" smd rect
			(at 4.59994 5.94995 90)
			(size 1.8034 0.508)
			(layers "F.Cu" "F.Mask" "F.Paste")
			(net "M_D_DQS_DN<0>")
		)
		(pad "153" smd rect
			(at 4.59994 6.800088 90)
			(size 1.8034 0.508)
			(layers "F.Cu" "F.Mask" "F.Paste")
			(net "M_D_DQS_DP<0>")
		)
		(pad "154" smd rect
			(at 4.59994 7.649972 90)
			(size 1.8034 0.508)
			(layers "F.Cu" "F.Mask" "F.Paste")
			(net "GND")
		)
		(pad "155" smd rect
			(at 4.59994 8.50011 90)
			(size 1.8034 0.508)
			(layers "F.Cu" "F.Mask" "F.Paste")
			(net "M_D_DQ<6>")
		)
		(pad "156" smd rect
			(at 4.59994 9.349994 90)
			(size 1.8034 0.508)
			(layers "F.Cu" "F.Mask" "F.Paste")
			(net "GND")
		)
		(pad "157" smd rect
			(at 4.59994 10.199878 90)
			(size 1.8034 0.508)
			(layers "F.Cu" "F.Mask" "F.Paste")
			(net "M_D_DQ<2>")
		)
		(pad "158" smd rect
			(at 4.59994 11.050016 90)
			(size 1.8034 0.508)
			(layers "F.Cu" "F.Mask" "F.Paste")
			(net "GND")
		)
		(pad "159" smd rect
			(at 4.59994 11.8999 90)
			(size 1.8034 0.508)
			(layers "F.Cu" "F.Mask" "F.Paste")
			(net "M_D_DQ<12>")
		)
		(pad "160" smd rect
			(at 4.59994 12.750038 90)
			(size 1.8034 0.508)
			(layers "F.Cu" "F.Mask" "F.Paste")
			(net "GND")
		)
		(pad "161" smd rect
			(at 4.59994 13.599922 90)
			(size 1.8034 0.508)
			(layers "F.Cu" "F.Mask" "F.Paste")
			(net "M_D_DQ<8>")
		)
		(pad "162" smd rect
			(at 4.59994 14.45006 90)
			(size 1.8034 0.508)
			(layers "F.Cu" "F.Mask" "F.Paste")
			(net "GND")
		)
		(pad "163" smd rect
			(at 4.59994 15.299944 90)
			(size 1.8034 0.508)
			(layers "F.Cu" "F.Mask" "F.Paste")
			(net "M_D_DQS_DN<1>")
		)
		(pad "164" smd rect
			(at 4.59994 16.150082 90)
			(size 1.8034 0.508)
			(layers "F.Cu" "F.Mask" "F.Paste")
			(net "M_D_DQS_DP<1>")
		)
		(pad "165" smd rect
			(at 4.59994 16.999966 90)
			(size 1.8034 0.508)
			(layers "F.Cu" "F.Mask" "F.Paste")
			(net "GND")
		)
		(pad "166" smd rect
			(at 4.59994 17.850104 90)
			(size 1.8034 0.508)
			(layers "F.Cu" "F.Mask" "F.Paste")
			(net "M_D_DQ<14>")
		)
		(pad "167" smd rect
			(at 4.59994 18.699988 90)
			(size 1.8034 0.508)
			(layers "F.Cu" "F.Mask" "F.Paste")
			(net "GND")
		)
		(pad "168" smd rect
			(at 4.59994 19.550126 90)
			(size 1.8034 0.508)
			(layers "F.Cu" "F.Mask" "F.Paste")
			(net "M_D_DQ<10>")
		)
		(pad "169" smd rect
			(at 4.59994 20.40001 90)
			(size 1.8034 0.508)
			(layers "F.Cu" "F.Mask" "F.Paste")
			(net "GND")
		)
		(pad "170" smd rect
			(at 4.59994 21.249894 90)
			(size 1.8034 0.508)
			(layers "F.Cu" "F.Mask" "F.Paste")
			(net "M_D_DQ<20>")
		)
		(pad "171" smd rect
			(at 4.59994 22.100032 90)
			(size 1.8034 0.508)
			(layers "F.Cu" "F.Mask" "F.Paste")
			(net "GND")
		)
		(pad "172" smd rect
			(at 4.59994 22.949916 90)
			(size 1.8034 0.508)
			(layers "F.Cu" "F.Mask" "F.Paste")
			(net "M_D_DQ<16>")
		)
		(pad "173" smd rect
			(at 4.59994 23.800054 90)
			(size 1.8034 0.508)
			(layers "F.Cu" "F.Mask" "F.Paste")
			(net "GND")
		)
		(pad "174" smd rect
			(at 4.59994 24.649938 90)
			(size 1.8034 0.508)
			(layers "F.Cu" "F.Mask" "F.Paste")
			(net "M_D_DQS_DN<2>")
		)
		(pad "175" smd rect
			(at 4.59994 25.500076 90)
			(size 1.8034 0.508)
			(layers "F.Cu" "F.Mask" "F.Paste")
			(net "M_D_DQS_DP<2>")
		)
		(pad "176" smd rect
			(at 4.59994 26.34996 90)
			(size 1.8034 0.508)
			(layers "F.Cu" "F.Mask" "F.Paste")
			(net "GND")
		)
		(pad "177" smd rect
			(at 4.59994 27.200098 90)
			(size 1.8034 0.508)
			(layers "F.Cu" "F.Mask" "F.Paste")
			(net "M_D_DQ<22>")
		)
		(pad "178" smd rect
			(at 4.59994 28.049982 90)
			(size 1.8034 0.508)
			(layers "F.Cu" "F.Mask" "F.Paste")
			(net "GND")
		)
		(pad "179" smd rect
			(at 4.59994 28.90012 90)
			(size 1.8034 0.508)
			(layers "F.Cu" "F.Mask" "F.Paste")
			(net "M_D_DQ<18>")
		)
		(pad "180" smd rect
			(at 4.59994 29.750004 90)
			(size 1.8034 0.508)
			(layers "F.Cu" "F.Mask" "F.Paste")
			(net "GND")
		)
		(pad "181" smd rect
			(at 4.59994 30.599888 90)
			(size 1.8034 0.508)
			(layers "F.Cu" "F.Mask" "F.Paste")
			(net "M_D_DQ<28>")
		)
		(pad "182" smd rect
			(at 4.59994 31.450026 90)
			(size 1.8034 0.508)
			(layers "F.Cu" "F.Mask" "F.Paste")
			(net "GND")
		)
		(pad "183" smd rect
			(at 4.59994 32.29991 90)
			(size 1.8034 0.508)
			(layers "F.Cu" "F.Mask" "F.Paste")
			(net "M_D_DQ<24>")
		)
		(pad "184" smd rect
			(at 4.59994 33.150048 90)
			(size 1.8034 0.508)
			(layers "F.Cu" "F.Mask" "F.Paste")
			(net "GND")
		)
		(pad "185" smd rect
			(at 4.59994 33.999932 90)
			(size 1.8034 0.508)
			(layers "F.Cu" "F.Mask" "F.Paste")
			(net "M_D_DQS_DN<3>")
		)
		(pad "186" smd rect
			(at 4.59994 34.85007 90)
			(size 1.8034 0.508)
			(layers "F.Cu" "F.Mask" "F.Paste")
			(net "M_D_DQS_DP<3>")
		)
		(pad "187" smd rect
			(at 4.59994 35.699954 90)
			(size 1.8034 0.508)
			(layers "F.Cu" "F.Mask" "F.Paste")
			(net "GND")
		)
		(pad "188" smd rect
			(at 4.59994 36.550092 90)
			(size 1.8034 0.508)
			(layers "F.Cu" "F.Mask" "F.Paste")
			(net "M_D_DQ<30>")
		)
		(pad "189" smd rect
			(at 4.59994 37.399976 90)
			(size 1.8034 0.508)
			(layers "F.Cu" "F.Mask" "F.Paste")
			(net "GND")
		)
		(pad "190" smd rect
			(at 4.59994 38.250114 90)
			(size 1.8034 0.508)
			(layers "F.Cu" "F.Mask" "F.Paste")
			(net "M_D_DQ<26>")
		)
		(pad "191" smd rect
			(at 4.59994 39.099998 90)
			(size 1.8034 0.508)
			(layers "F.Cu" "F.Mask" "F.Paste")
			(net "GND")
		)
		(pad "192" smd rect
			(at 4.59994 39.949882 90)
			(size 1.8034 0.508)
			(layers "F.Cu" "F.Mask" "F.Paste")
			(net "M_D_ECC<4>")
		)
		(pad "193" smd rect
			(at 4.59994 40.80002 90)
			(size 1.8034 0.508)
			(layers "F.Cu" "F.Mask" "F.Paste")
			(net "GND")
		)
		(pad "194" smd rect
			(at 4.59994 41.649904 90)
			(size 1.8034 0.508)
			(layers "F.Cu" "F.Mask" "F.Paste")
			(net "M_D_ECC<0>")
		)
		(pad "195" smd rect
			(at 4.59994 42.500042 90)
			(size 1.8034 0.508)
			(layers "F.Cu" "F.Mask" "F.Paste")
			(net "GND")
		)
		(pad "196" smd rect
			(at 4.59994 43.349926 90)
			(size 1.8034 0.508)
			(layers "F.Cu" "F.Mask" "F.Paste")
			(net "M_D_DQS_DN<8>")
		)
		(pad "197" smd rect
			(at 4.59994 44.200064 90)
			(size 1.8034 0.508)
			(layers "F.Cu" "F.Mask" "F.Paste")
			(net "M_D_DQS_DP<8>")
		)
		(pad "198" smd rect
			(at 4.59994 45.049948 90)
			(size 1.8034 0.508)
			(layers "F.Cu" "F.Mask" "F.Paste")
			(net "GND")
		)
		(pad "199" smd rect
			(at 4.59994 45.900086 90)
			(size 1.8034 0.508)
			(layers "F.Cu" "F.Mask" "F.Paste")
			(net "M_D_ECC<6>")
		)
		(pad "200" smd rect
			(at 4.59994 46.74997 90)
			(size 1.8034 0.508)
			(layers "F.Cu" "F.Mask" "F.Paste")
			(net "GND")
		)
		(pad "201" smd rect
			(at 4.59994 47.600108 90)
			(size 1.8034 0.508)
			(layers "F.Cu" "F.Mask" "F.Paste")
			(net "M_D_ECC<2>")
		)
		(pad "202" smd rect
			(at 4.59994 48.449992 90)
			(size 1.8034 0.508)
			(layers "F.Cu" "F.Mask" "F.Paste")
			(net "GND")
		)
		(pad "203" smd rect
			(at 4.59994 49.299876 90)
			(size 1.8034 0.508)
			(layers "F.Cu" "F.Mask" "F.Paste")
			(net "M_D_CKE<1>")
		)
		(pad "204" smd rect
			(at 4.59994 50.150014 90)
			(size 1.8034 0.508)
			(layers "F.Cu" "F.Mask" "F.Paste")
			(net "PVDDQ_DEF")
		)
		(pad "205" smd rect
			(at 4.59994 50.999898 90)
			(size 1.8034 0.508)
			(layers "F.Cu" "F.Mask" "F.Paste")
			(net "TP_CH_D_DIMM_D0_RFU_0")
		)
		(pad "206" smd rect
			(at 4.59994 51.850036 90)
			(size 1.8034 0.508)
			(layers "F.Cu" "F.Mask" "F.Paste")
			(net "PVDDQ_DEF")
		)
		(pad "207" smd rect
			(at 4.59994 52.69992 90)
			(size 1.8034 0.508)
			(layers "F.Cu" "F.Mask" "F.Paste")
			(net "M_D_BG<1>")
		)
		(pad "208" smd rect
			(at 4.59994 53.550058 90)
			(size 1.8034 0.508)
			(layers "F.Cu" "F.Mask" "F.Paste")
			(net "M_D_ALERT_N")
		)
		(pad "209" smd rect
			(at 4.59994 54.399942 90)
			(size 1.8034 0.508)
			(layers "F.Cu" "F.Mask" "F.Paste")
			(net "PVDDQ_DEF")
		)
		(pad "210" smd rect
			(at 4.59994 55.25008 90)
			(size 1.8034 0.508)
			(layers "F.Cu" "F.Mask" "F.Paste")
			(net "M_D_MA<11>")
		)
		(pad "211" smd rect
			(at 4.59994 56.099964 90)
			(size 1.8034 0.508)
			(layers "F.Cu" "F.Mask" "F.Paste")
			(net "M_D_MA<7>")
		)
		(pad "212" smd rect
			(at 4.59994 56.950102 90)
			(size 1.8034 0.508)
			(layers "F.Cu" "F.Mask" "F.Paste")
			(net "PVDDQ_DEF")
		)
		(pad "213" smd rect
			(at 4.59994 57.799986 90)
			(size 1.8034 0.508)
			(layers "F.Cu" "F.Mask" "F.Paste")
			(net "M_D_MA<5>")
		)
		(pad "214" smd rect
			(at 4.59994 58.650124 90)
			(size 1.8034 0.508)
			(layers "F.Cu" "F.Mask" "F.Paste")
			(net "M_D_MA<4>")
		)
		(pad "215" smd rect
			(at 4.59994 59.500008 90)
			(size 1.8034 0.508)
			(layers "F.Cu" "F.Mask" "F.Paste")
			(net "PVDDQ_DEF")
		)
		(pad "216" smd rect
			(at 4.59994 60.349892 90)
			(size 1.8034 0.508)
			(layers "F.Cu" "F.Mask" "F.Paste")
			(net "M_D_MA<2>")
		)
		(pad "217" smd rect
			(at 4.59994 61.20003 90)
			(size 1.8034 0.508)
			(layers "F.Cu" "F.Mask" "F.Paste")
			(net "PVDDQ_DEF")
		)
		(pad "218" smd rect
			(at 4.59994 62.049914 90)
			(size 1.8034 0.508)
			(layers "F.Cu" "F.Mask" "F.Paste")
			(net "M_D_CLK_DP<1>")
		)
		(pad "219" smd rect
			(at 4.59994 62.900052 90)
			(size 1.8034 0.508)
			(layers "F.Cu" "F.Mask" "F.Paste")
			(net "M_D_CLK_DN<1>")
		)
		(pad "220" smd rect
			(at 4.59994 63.749936 90)
			(size 1.8034 0.508)
			(layers "F.Cu" "F.Mask" "F.Paste")
			(net "PVDDQ_DEF")
		)
		(pad "221" smd rect
			(at 4.59994 64.600074 90)
			(size 1.8034 0.508)
			(layers "F.Cu" "F.Mask" "F.Paste")
			(net "PVTT_DEF")
		)
		(pad "222" smd rect
			(at 4.59994 70.550024 90)
			(size 1.8034 0.508)
			(layers "F.Cu" "F.Mask" "F.Paste")
			(net "M_D_PAR")
		)
		(pad "223" smd rect
			(at 4.59994 71.399908 90)
			(size 1.8034 0.508)
			(layers "F.Cu" "F.Mask" "F.Paste")
			(net "PVDDQ_DEF")
		)
		(pad "224" smd rect
			(at 4.59994 72.250046 90)
			(size 1.8034 0.508)
			(layers "F.Cu" "F.Mask" "F.Paste")
			(net "M_D_BA<1>")
		)
		(pad "225" smd rect
			(at 4.59994 73.09993 90)
			(size 1.8034 0.508)
			(layers "F.Cu" "F.Mask" "F.Paste")
			(net "M_D_MA<10>")
		)
		(pad "226" smd rect
			(at 4.59994 73.950068 90)
			(size 1.8034 0.508)
			(layers "F.Cu" "F.Mask" "F.Paste")
			(net "PVDDQ_DEF")
		)
		(pad "227" smd rect
			(at 4.59994 74.799952 90)
			(size 1.8034 0.508)
			(layers "F.Cu" "F.Mask" "F.Paste")
			(net "TP_CH_D_DIMM_D0_RFU_1")
		)
		(pad "228" smd rect
			(at 4.59994 75.65009 90)
			(size 1.8034 0.508)
			(layers "F.Cu" "F.Mask" "F.Paste")
			(net "M_D_MA<14>")
		)
		(pad "229" smd rect
			(at 4.59994 76.499974 90)
			(size 1.8034 0.508)
			(layers "F.Cu" "F.Mask" "F.Paste")
			(net "PVDDQ_DEF")
		)
		(pad "230" smd rect
			(at 4.59994 77.350112 90)
			(size 1.8034 0.508)
			(layers "F.Cu" "F.Mask" "F.Paste")
			(net "FM_ADR_COMPLETE_DEF_N")
		)
		(pad "231" smd rect
			(at 4.59994 78.199996 90)
			(size 1.8034 0.508)
			(layers "F.Cu" "F.Mask" "F.Paste")
			(net "PVDDQ_DEF")
		)
		(pad "232" smd rect
			(at 4.59994 79.04988 90)
			(size 1.8034 0.508)
			(layers "F.Cu" "F.Mask" "F.Paste")
			(net "M_D_MA<13>")
		)
		(pad "233" smd rect
			(at 4.59994 79.900018 90)
			(size 1.8034 0.508)
			(layers "F.Cu" "F.Mask" "F.Paste")
			(net "PVDDQ_DEF")
		)
		(pad "234" smd rect
			(at 4.59994 80.749902 90)
			(size 1.8034 0.508)
			(layers "F.Cu" "F.Mask" "F.Paste")
			(net "M_D_MA<17>")
		)
		(pad "235" smd rect
			(at 4.59994 81.60004 90)
			(size 1.8034 0.508)
			(layers "F.Cu" "F.Mask" "F.Paste")
			(net "M_D_C<2>")
		)
		(pad "236" smd rect
			(at 4.59994 82.449924 90)
			(size 1.8034 0.508)
			(layers "F.Cu" "F.Mask" "F.Paste")
			(net "PVDDQ_DEF")
		)
		(pad "237" smd rect
			(at 4.59994 83.300062 90)
			(size 1.8034 0.508)
			(layers "F.Cu" "F.Mask" "F.Paste")
			(net "M_D_CS_N<3>")
		)
		(pad "238" smd rect
			(at 4.59994 84.149946 90)
			(size 1.8034 0.508)
			(layers "F.Cu" "F.Mask" "F.Paste")
			(net "GND")
		)
		(pad "239" smd rect
			(at 4.59994 85.000084 90)
			(size 1.8034 0.508)
			(layers "F.Cu" "F.Mask" "F.Paste")
			(net "GND")
		)
		(pad "240" smd rect
			(at 4.59994 85.849968 90)
			(size 1.8034 0.508)
			(layers "F.Cu" "F.Mask" "F.Paste")
			(net "M_D_DQ<36>")
		)
	)
)
